(kicad_pcb
	(version 20260206)
	(generator "pcbnew")
	(generator_version "10.0")
	(general
		(thickness 1.6)
		(legacy_teardrops no)
	)
	(paper "A4")
	(title_block
		(title "baseboard — 13948-1b.1110WZS1818.brd")
		(comment 1 "Honey Badger (Wiwynn) / footprints 1086-1092 of 2523")
	)
	(layers
		(0 "F.Cu" signal "TOP")
		(4 "In1.Cu" signal "L2GND")
		(6 "In2.Cu" signal "L3")
		(8 "In3.Cu" signal "L4VCC")
		(10 "In4.Cu" signal "L5VCC")
		(12 "In5.Cu" signal "L6")
		(14 "In6.Cu" signal "L7GND")
		(2 "B.Cu" signal "BOTTOM")
		(9 "F.Adhes" user "F.Adhesive")
		(11 "B.Adhes" user "B.Adhesive")
		(13 "F.Paste" user "Package Geometry/Pastemask Top")
		(15 "B.Paste" user "Package Geometry/Pastemask Bottom")
		(5 "F.SilkS" user "Ref Des/Silkscreen Top")
		(7 "B.SilkS" user "Ref Des/Silkscreen Bottom")
		(1 "F.Mask" user "Board Geometry/Soldermask Top")
		(3 "B.Mask" user "Board Geometry/Soldermask Bottom")
		(17 "Dwgs.User" user "User.Drawings")
		(19 "Cmts.User" user "User.Comments")
		(21 "Eco1.User" user "User.Eco1")
		(23 "Eco2.User" user "User.Eco2")
		(25 "Edge.Cuts" user "Board Geometry/Outline")
		(27 "Margin" user)
		(31 "F.CrtYd" user "Package Geometry/Place Bound Top")
		(29 "B.CrtYd" user "Package Geometry/Place Bound Bottom")
		(35 "F.Fab" user "Ref Des/Assembly Top")
		(33 "B.Fab" user "Ref Des/Assembly Bottom")
	)
	(footprint ""
		(layer "F.Cu")
		(at 333.828136 -200.033128)
		(property "Reference" "R199"
			(at 0 0 0)
			(layer "F.SilkS")
			(hide yes)
			(effects
				(font
					(size 1.27 1.27)
				)
			)
		)
		(property "Value" "8K2R2J-3-GP"
			(at 0.064008 -3.993896 0)
			(unlocked yes)
			(layer "F.Fab")
			(hide yes)
			(effects
				(font
					(size 1.016 1.016)
					(thickness 0.1524)
				)
			)
		)
		(property "Device Type" "R402H16"
			(at 0.064008 -5.517896 0)
			(unlocked yes)
			(layer "F.Fab")
			(hide yes)
			(effects
				(font
					(size 1.016 1.016)
					(thickness 0.1524)
				)
			)
		)
		(duplicate_pad_numbers_are_jumpers no)
		(fp_line
			(start -0.508 -0.9398)
			(end -0.508 0.9398)
			(stroke
				(width 0.1524)
				(type default)
			)
			(layer "F.SilkS")
		)
		(fp_line
			(start 0.508 -0.9398)
			(end -0.508 -0.9398)
			(stroke
				(width 0.1524)
				(type default)
			)
			(layer "F.SilkS")
		)
		(fp_rect
			(start -0.508 0.9398)
			(end 0.508 -0.9398)
			(stroke
				(width 0)
				(type default)
			)
			(fill no)
			(layer "F.CrtYd")
		)
		(fp_rect
			(start -0.508 0.9398)
			(end 0.508 -0.9398)
			(stroke
				(width 0)
				(type default)
			)
			(fill no)
			(layer "F.Fab")
		)
		(pad "1" smd custom
			(at 0 -0.4445)
			(size 0.1397 0.1397)
			(layers "F.Cu" "F.Mask" "F.Paste")
			(net "EEPROM_A2_R")
			(options
				(clearance outline)
				(anchor circle)
			)
			(primitives
				(gr_poly
					(pts
						(arc
							(start -0.1778 -0.2794)
							(mid -0.249642 -0.249642)
							(end -0.2794 -0.1778)
						)
						(arc
							(start -0.2794 0.1778)
							(mid -0.249642 0.249642)
							(end -0.1778 0.2794)
						)
						(arc
							(start 0.1778 0.2794)
							(mid 0.249642 0.249642)
							(end 0.2794 0.1778)
						)
						(arc
							(start 0.2794 -0.1778)
							(mid 0.249642 -0.249642)
							(end 0.1778 -0.2794)
						)
					)
					(width 0)
					(fill yes)
				)
			)
		)
		(pad "2" smd custom
			(at 0 0.4445)
			(size 0.1397 0.1397)
			(layers "F.Cu" "F.Mask" "F.Paste")
			(net "GND")
			(options
				(clearance outline)
				(anchor circle)
			)
			(primitives
				(gr_poly
					(pts
						(arc
							(start -0.1778 -0.2794)
							(mid -0.249642 -0.249642)
							(end -0.2794 -0.1778)
						)
						(arc
							(start -0.2794 0.1778)
							(mid -0.249642 0.249642)
							(end -0.1778 0.2794)
						)
						(arc
							(start 0.1778 0.2794)
							(mid 0.249642 0.249642)
							(end 0.2794 0.1778)
						)
						(arc
							(start 0.2794 -0.1778)
							(mid 0.249642 -0.249642)
							(end 0.1778 -0.2794)
						)
					)
					(width 0)
					(fill yes)
				)
			)
		)
	)
	(footprint ""
		(layer "F.Cu")
		(at 265.049 -25.019 -90)
		(property "Reference" "PC57"
			(at 0 0 270)
			(layer "F.SilkS")
			(hide yes)
			(effects
				(font
					(size 1.27 1.27)
				)
			)
		)
		(property "Value" "SC100U6D3V6MX-GP"
			(at -0.0762 -5.1308 270)
			(unlocked yes)
			(layer "F.Fab")
			(hide yes)
			(effects
				(font
					(size 1.016 1.016)
					(thickness 0.1524)
				)
			)
		)
		(property "Device Type" "C1206H71"
			(at -0.127 -6.6548 270)
			(unlocked yes)
			(layer "F.Fab")
			(hide yes)
			(effects
				(font
					(size 1.016 1.016)
					(thickness 0.1524)
				)
			)
		)
		(duplicate_pad_numbers_are_jumpers no)
		(fp_line
			(start -1.016 2.2352)
			(end -1.016 0.8382)
			(stroke
				(width 0.1524)
				(type default)
			)
			(layer "F.SilkS")
		)
		(fp_line
			(start 1.016 2.2352)
			(end -1.016 2.2352)
			(stroke
				(width 0.1524)
				(type default)
			)
			(layer "F.SilkS")
		)
		(fp_line
			(start 1.016 0.8382)
			(end 1.016 2.2352)
			(stroke
				(width 0.1524)
				(type default)
			)
			(layer "F.SilkS")
		)
		(fp_line
			(start -1.016 -0.8382)
			(end -1.016 -2.2352)
			(stroke
				(width 0.1524)
				(type default)
			)
			(layer "F.SilkS")
		)
		(fp_line
			(start -1.016 -2.2352)
			(end 1.016 -2.2352)
			(stroke
				(width 0.1524)
				(type default)
			)
			(layer "F.SilkS")
		)
		(fp_line
			(start 1.016 -2.2352)
			(end 1.016 -0.8382)
			(stroke
				(width 0.1524)
				(type default)
			)
			(layer "F.SilkS")
		)
		(fp_rect
			(start -1.0922 2.3114)
			(end 1.0922 -2.3114)
			(stroke
				(width 0)
				(type default)
			)
			(fill no)
			(layer "F.CrtYd")
		)
		(fp_poly
			(pts
				(xy 1.0922 -2.3114) (xy 1.0922 2.3114) (xy -1.0922 2.3114) (xy -1.0922 -2.3114)
			)
			(stroke
				(width 0)
				(type default)
			)
			(fill no)
			(layer "F.Fab")
		)
		(pad "1" smd rect
			(at 0 -1.397 270)
			(size 1.651 1.27)
			(layers "F.Cu" "F.Mask" "F.Paste")
			(net "P1V8_STBY")
		)
		(pad "2" smd rect
			(at 0 1.397 270)
			(size 1.651 1.27)
			(layers "F.Cu" "F.Mask" "F.Paste")
			(net "GND")
		)
	)
	(footprint ""
		(layer "F.Cu")
		(at 308.991 -186.817 -90)
		(property "Reference" "SR847"
			(at 0 0 270)
			(layer "F.SilkS")
			(hide yes)
			(effects
				(font
					(size 1.27 1.27)
				)
			)
		)
		(property "Value" "4K75R2F-1-GP"
			(at 0.064008 -3.993896 270)
			(unlocked yes)
			(layer "F.Fab")
			(hide yes)
			(effects
				(font
					(size 1.016 1.016)
					(thickness 0.1524)
				)
			)
		)
		(property "Device Type" "R402H16"
			(at 0.064008 -5.517896 270)
			(unlocked yes)
			(layer "F.Fab")
			(hide yes)
			(effects
				(font
					(size 1.016 1.016)
					(thickness 0.1524)
				)
			)
		)
		(duplicate_pad_numbers_are_jumpers no)
		(fp_line
			(start -0.508 -0.9398)
			(end -0.508 0.9398)
			(stroke
				(width 0.1524)
				(type default)
			)
			(layer "F.SilkS")
		)
		(fp_line
			(start 0.508 -0.9398)
			(end -0.508 -0.9398)
			(stroke
				(width 0.1524)
				(type default)
			)
			(layer "F.SilkS")
		)
		(fp_rect
			(start -0.508 0.9398)
			(end 0.508 -0.9398)
			(stroke
				(width 0)
				(type default)
			)
			(fill no)
			(layer "F.CrtYd")
		)
		(fp_rect
			(start -0.508 0.9398)
			(end 0.508 -0.9398)
			(stroke
				(width 0)
				(type default)
			)
			(fill no)
			(layer "F.Fab")
		)
		(pad "1" smd custom
			(at 0 -0.4445 270)
			(size 0.1397 0.1397)
			(layers "F.Cu" "F.Mask" "F.Paste")
			(net "BMC_FW_DET_BOARD_VER_2")
			(options
				(clearance outline)
				(anchor circle)
			)
			(primitives
				(gr_poly
					(pts
						(arc
							(start -0.1778 -0.2794)
							(mid -0.249642 -0.249642)
							(end -0.2794 -0.1778)
						)
						(arc
							(start -0.2794 0.1778)
							(mid -0.249642 0.249642)
							(end -0.1778 0.2794)
						)
						(arc
							(start 0.1778 0.2794)
							(mid 0.249642 0.249642)
							(end 0.2794 0.1778)
						)
						(arc
							(start 0.2794 -0.1778)
							(mid 0.249642 -0.249642)
							(end 0.1778 -0.2794)
						)
					)
					(width 0)
					(fill yes)
				)
			)
		)
		(pad "2" smd custom
			(at 0 0.4445 270)
			(size 0.1397 0.1397)
			(layers "F.Cu" "F.Mask" "F.Paste")
			(net "GND")
			(options
				(clearance outline)
				(anchor circle)
			)
			(primitives
				(gr_poly
					(pts
						(arc
							(start -0.1778 -0.2794)
							(mid -0.249642 -0.249642)
							(end -0.2794 -0.1778)
						)
						(arc
							(start -0.2794 0.1778)
							(mid -0.249642 0.249642)
							(end -0.1778 0.2794)
						)
						(arc
							(start 0.1778 0.2794)
							(mid 0.249642 0.249642)
							(end 0.2794 0.1778)
						)
						(arc
							(start 0.2794 -0.1778)
							(mid 0.249642 -0.249642)
							(end 0.1778 -0.2794)
						)
					)
					(width 0)
					(fill yes)
				)
			)
		)
	)
	(footprint ""
		(layer "F.Cu")
		(at 173.628304 -24.113236 90)
		(property "Reference" "R404"
			(at 0 0 90)
			(layer "F.SilkS")
			(hide yes)
			(effects
				(font
					(size 1.27 1.27)
				)
			)
		)
		(property "Value" "49D9R2F-GP"
			(at 0.064008 -3.993896 90)
			(unlocked yes)
			(layer "F.Fab")
			(hide yes)
			(effects
				(font
					(size 1.016 1.016)
					(thickness 0.1524)
				)
			)
		)
		(property "Device Type" "R402H16"
			(at 0.064008 -5.517896 90)
			(unlocked yes)
			(layer "F.Fab")
			(hide yes)
			(effects
				(font
					(size 1.016 1.016)
					(thickness 0.1524)
				)
			)
		)
		(duplicate_pad_numbers_are_jumpers no)
		(fp_line
			(start 0.508 -0.9398)
			(end -0.508 -0.9398)
			(stroke
				(width 0.1524)
				(type default)
			)
			(layer "F.SilkS")
		)
		(fp_line
			(start -0.508 -0.9398)
			(end -0.508 0.9398)
			(stroke
				(width 0.1524)
				(type default)
			)
			(layer "F.SilkS")
		)
		(fp_rect
			(start -0.508 0.9398)
			(end 0.508 -0.9398)
			(stroke
				(width 0)
				(type default)
			)
			(fill no)
			(layer "F.CrtYd")
		)
		(fp_rect
			(start -0.508 0.9398)
			(end 0.508 -0.9398)
			(stroke
				(width 0)
				(type default)
			)
			(fill no)
			(layer "F.Fab")
		)
		(pad "1" smd custom
			(at 0 -0.4445 90)
			(size 0.1397 0.1397)
			(layers "F.Cu" "F.Mask" "F.Paste")
			(net "MOD_IMC_FAB_D_COP")
			(options
				(clearance outline)
				(anchor circle)
			)
			(primitives
				(gr_poly
					(pts
						(arc
							(start -0.1778 -0.2794)
							(mid -0.249642 -0.249642)
							(end -0.2794 -0.1778)
						)
						(arc
							(start -0.2794 0.1778)
							(mid -0.249642 0.249642)
							(end -0.1778 0.2794)
						)
						(arc
							(start 0.1778 0.2794)
							(mid 0.249642 0.249642)
							(end 0.2794 0.1778)
						)
						(arc
							(start 0.2794 -0.1778)
							(mid 0.249642 -0.249642)
							(end 0.1778 -0.2794)
						)
					)
					(width 0)
					(fill yes)
				)
			)
		)
		(pad "2" smd custom
			(at 0 0.4445 90)
			(size 0.1397 0.1397)
			(layers "F.Cu" "F.Mask" "F.Paste")
			(net "BCM5221_TX_C_DP")
			(options
				(clearance outline)
				(anchor circle)
			)
			(primitives
				(gr_poly
					(pts
						(arc
							(start -0.1778 -0.2794)
							(mid -0.249642 -0.249642)
							(end -0.2794 -0.1778)
						)
						(arc
							(start -0.2794 0.1778)
							(mid -0.249642 0.249642)
							(end -0.1778 0.2794)
						)
						(arc
							(start 0.1778 0.2794)
							(mid 0.249642 0.249642)
							(end 0.2794 0.1778)
						)
						(arc
							(start 0.2794 -0.1778)
							(mid 0.249642 -0.249642)
							(end 0.1778 -0.2794)
						)
					)
					(width 0)
					(fill yes)
				)
			)
		)
	)
	(footprint ""
		(layer "F.Cu")
		(at 332.431136 -197.366128 180)
		(property "Reference" "R193"
			(at 0 0 180)
			(layer "F.SilkS")
			(hide yes)
			(effects
				(font
					(size 1.27 1.27)
				)
			)
		)
		(property "Value" "8K2R2J-3-GP"
			(at 0.064008 -3.993896 180)
			(unlocked yes)
			(layer "F.Fab")
			(hide yes)
			(effects
				(font
					(size 1.016 1.016)
					(thickness 0.1524)
				)
			)
		)
		(property "Device Type" "R402H16"
			(at 0.064008 -5.517896 180)
			(unlocked yes)
			(layer "F.Fab")
			(hide yes)
			(effects
				(font
					(size 1.016 1.016)
					(thickness 0.1524)
				)
			)
		)
		(duplicate_pad_numbers_are_jumpers no)
		(fp_line
			(start 0.508 -0.9398)
			(end -0.508 -0.9398)
			(stroke
				(width 0.1524)
				(type default)
			)
			(layer "F.SilkS")
		)
		(fp_line
			(start -0.508 -0.9398)
			(end -0.508 0.9398)
			(stroke
				(width 0.1524)
				(type default)
			)
			(layer "F.SilkS")
		)
		(fp_rect
			(start -0.508 0.9398)
			(end 0.508 -0.9398)
			(stroke
				(width 0)
				(type default)
			)
			(fill no)
			(layer "F.CrtYd")
		)
		(fp_rect
			(start -0.508 0.9398)
			(end 0.508 -0.9398)
			(stroke
				(width 0)
				(type default)
			)
			(fill no)
			(layer "F.Fab")
		)
		(pad "1" smd custom
			(at 0 -0.4445 180)
			(size 0.1397 0.1397)
			(layers "F.Cu" "F.Mask" "F.Paste")
			(net "P3V3_STBY")
			(options
				(clearance outline)
				(anchor circle)
			)
			(primitives
				(gr_poly
					(pts
						(arc
							(start -0.1778 -0.2794)
							(mid -0.249642 -0.249642)
							(end -0.2794 -0.1778)
						)
						(arc
							(start -0.2794 0.1778)
							(mid -0.249642 0.249642)
							(end -0.1778 0.2794)
						)
						(arc
							(start 0.1778 0.2794)
							(mid 0.249642 0.249642)
							(end 0.2794 0.1778)
						)
						(arc
							(start 0.2794 -0.1778)
							(mid 0.249642 -0.249642)
							(end 0.1778 -0.2794)
						)
					)
					(width 0)
					(fill yes)
				)
			)
		)
		(pad "2" smd custom
			(at 0 0.4445 180)
			(size 0.1397 0.1397)
			(layers "F.Cu" "F.Mask" "F.Paste")
			(net "EEPROM_A1_R")
			(options
				(clearance outline)
				(anchor circle)
			)
			(primitives
				(gr_poly
					(pts
						(arc
							(start -0.1778 -0.2794)
							(mid -0.249642 -0.249642)
							(end -0.2794 -0.1778)
						)
						(arc
							(start -0.2794 0.1778)
							(mid -0.249642 0.249642)
							(end -0.1778 0.2794)
						)
						(arc
							(start 0.1778 0.2794)
							(mid 0.249642 0.249642)
							(end 0.2794 0.1778)
						)
						(arc
							(start 0.2794 -0.1778)
							(mid 0.249642 -0.249642)
							(end 0.1778 -0.2794)
						)
					)
					(width 0)
					(fill yes)
				)
			)
		)
	)
	(footprint ""
		(layer "F.Cu")
		(at 222.123 -96.393 -90)
		(property "Reference" "PR120"
			(at 0 0 270)
			(layer "F.SilkS")
			(hide yes)
			(effects
				(font
					(size 1.27 1.27)
				)
			)
		)
		(property "Value" "0R6J-3-GP"
			(at -0.0508 -4.8514 270)
			(unlocked yes)
			(layer "F.Fab")
			(hide yes)
			(effects
				(font
					(size 1.016 1.016)
					(thickness 0.1524)
				)
			)
		)
		(property "Device Type" "R1206H28"
			(at 0 -6.3754 270)
			(unlocked yes)
			(layer "F.Fab")
			(hide yes)
			(effects
				(font
					(size 1.016 1.016)
					(thickness 0.1524)
				)
			)
		)
		(duplicate_pad_numbers_are_jumpers no)
		(fp_line
			(start -1.016 2.2352)
			(end -1.016 -2.2352)
			(stroke
				(width 0.1524)
				(type default)
			)
			(layer "F.SilkS")
		)
		(fp_line
			(start 1.016 2.2352)
			(end -1.016 2.2352)
			(stroke
				(width 0.1524)
				(type default)
			)
			(layer "F.SilkS")
		)
		(fp_line
			(start -1.016 -2.2352)
			(end 1.016 -2.2352)
			(stroke
				(width 0.1524)
				(type default)
			)
			(layer "F.SilkS")
		)
		(fp_line
			(start 1.016 -2.2352)
			(end 1.016 2.2352)
			(stroke
				(width 0.1524)
				(type default)
			)
			(layer "F.SilkS")
		)
		(fp_rect
			(start -1.0922 2.3114)
			(end 1.0922 -2.3114)
			(stroke
				(width 0)
				(type default)
			)
			(fill no)
			(layer "F.CrtYd")
		)
		(fp_poly
			(pts
				(xy -1.0922 -2.3114) (xy 1.0922 -2.3114) (xy 1.0922 2.3114) (xy -1.0922 2.3114)
			)
			(stroke
				(width 0)
				(type default)
			)
			(fill no)
			(layer "F.Fab")
		)
		(pad "1" smd rect
			(at 0 -1.397 270)
			(size 1.651 1.27)
			(layers "F.Cu" "F.Mask" "F.Paste")
			(net "P1V8_STBY")
		)
		(pad "2" smd rect
			(at 0 1.397 270)
			(size 1.651 1.27)
			(layers "F.Cu" "F.Mask" "F.Paste")
			(net "TPS74801_P1V5_C_IN")
		)
	)
	(footprint ""
		(layer "F.Cu")
		(at 95.89897 -80.518 -90)
		(property "Reference" "SR800"
			(at 0 0 270)
			(layer "F.SilkS")
			(hide yes)
			(effects
				(font
					(size 1.27 1.27)
				)
			)
		)
		(property "Value" "4K75R2F-1-GP"
			(at 0.064008 -3.993896 270)
			(unlocked yes)
			(layer "F.Fab")
			(hide yes)
			(effects
				(font
					(size 1.016 1.016)
					(thickness 0.1524)
				)
			)
		)
		(property "Device Type" "R402H16"
			(at 0.064008 -5.517896 270)
			(unlocked yes)
			(layer "F.Fab")
			(hide yes)
			(effects
				(font
					(size 1.016 1.016)
					(thickness 0.1524)
				)
			)
		)
		(duplicate_pad_numbers_are_jumpers no)
		(fp_line
			(start -0.508 -0.9398)
			(end -0.508 0.9398)
			(stroke
				(width 0.1524)
				(type default)
			)
			(layer "F.SilkS")
		)
		(fp_line
			(start 0.508 -0.9398)
			(end -0.508 -0.9398)
			(stroke
				(width 0.1524)
				(type default)
			)
			(layer "F.SilkS")
		)
		(fp_rect
			(start -0.508 0.9398)
			(end 0.508 -0.9398)
			(stroke
				(width 0)
				(type default)
			)
			(fill no)
			(layer "F.CrtYd")
		)
		(fp_rect
			(start -0.508 0.9398)
			(end 0.508 -0.9398)
			(stroke
				(width 0)
				(type default)
			)
			(fill no)
			(layer "F.Fab")
		)
		(pad "1" smd custom
			(at 0 -0.4445 270)
			(size 0.1397 0.1397)
			(layers "F.Cu" "F.Mask" "F.Paste")
			(net "TMUX_EN")
			(options
				(clearance outline)
				(anchor circle)
			)
			(primitives
				(gr_poly
					(pts
						(arc
							(start -0.1778 -0.2794)
							(mid -0.249642 -0.249642)
							(end -0.2794 -0.1778)
						)
						(arc
							(start -0.2794 0.1778)
							(mid -0.249642 0.249642)
							(end -0.1778 0.2794)
						)
						(arc
							(start 0.1778 0.2794)
							(mid 0.249642 0.249642)
							(end 0.2794 0.1778)
						)
						(arc
							(start 0.2794 -0.1778)
							(mid 0.249642 -0.249642)
							(end 0.1778 -0.2794)
						)
					)
					(width 0)
					(fill yes)
				)
			)
		)
		(pad "2" smd custom
			(at 0 0.4445 270)
			(size 0.1397 0.1397)
			(layers "F.Cu" "F.Mask" "F.Paste")
			(net "GND")
			(options
				(clearance outline)
				(anchor circle)
			)
			(primitives
				(gr_poly
					(pts
						(arc
							(start -0.1778 -0.2794)
							(mid -0.249642 -0.249642)
							(end -0.2794 -0.1778)
						)
						(arc
							(start -0.2794 0.1778)
							(mid -0.249642 0.249642)
							(end -0.1778 0.2794)
						)
						(arc
							(start 0.1778 0.2794)
							(mid 0.249642 0.249642)
							(end 0.2794 0.1778)
						)
						(arc
							(start 0.2794 -0.1778)
							(mid 0.249642 -0.249642)
							(end 0.1778 -0.2794)
						)
					)
					(width 0)
					(fill yes)
				)
			)
		)
	)
)
